# TIMECARD (Time Appliance Project (Time Card)) — schematic netlist excerpt (pin names and nets, part order shuffled) for the footprints in the layout excerpt that follows; sources: Cadence DE-HDL packaged netlist, KiCad conversion of R4006-B0001-02_R01.brd

R128  RESISTOR  0OHM -  pkg SMC_0402R_H016  page 24 : \1\ = FT_USB_DM ; \2\ = R_FT_USB_DM
C33  CAPACITOR  0.1UF 25V 10%  pkg SMC_0402R_H022  page 32 : \1\ = VIN_XP5R0V ; \2\ = SG

(kicad_pcb
	(version 20260206)
	(generator "pcbnew")
	(generator_version "10.0")
	(general
		(thickness 1.6)
		(legacy_teardrops no)
	)
	(paper "A4")
	(title_block
		(title "timecard-production-celestica-r4006 — R4006-B0001-02_R01.brd")
		(comment 1 "Time Appliance Project (Time Card) / footprints 504-505 of 1113")
	)
	(layers
		(0 "F.Cu" signal "TOP")
		(4 "In1.Cu" signal "L02_GND1")
		(6 "In2.Cu" signal "L03_SIG1")
		(8 "In3.Cu" signal "L04_GND2")
		(10 "In4.Cu" signal "L05_VCC1")
		(12 "In5.Cu" signal "L06_VCC2")
		(14 "In6.Cu" signal "L07_GND3")
		(16 "In7.Cu" signal "L08_SIG2")
		(18 "In8.Cu" signal "L09_GND4")
		(2 "B.Cu" signal "BOTTOM")
		(9 "F.Adhes" user "F.Adhesive")
		(11 "B.Adhes" user "B.Adhesive")
		(13 "F.Paste" user "Package Geometry/Pastemask Top")
		(15 "B.Paste" user "Package Geometry/Pastemask Bottom")
		(5 "F.SilkS" user "Ref Des/Silkscreen Top")
		(7 "B.SilkS" user "Ref Des/Silkscreen Bottom")
		(1 "F.Mask" user "Board Geometry/Soldermask Top")
		(3 "B.Mask" user "Board Geometry/Soldermask Bottom")
		(17 "Dwgs.User" user "User.Drawings")
		(19 "Cmts.User" user "User.Comments")
		(21 "Eco1.User" user "User.Eco1")
		(23 "Eco2.User" user "User.Eco2")
		(25 "Edge.Cuts" user "Board Geometry/Outline")
		(27 "Margin" user)
		(31 "F.CrtYd" user "Package Geometry/Place Bound Top")
		(29 "B.CrtYd" user "Package Geometry/Place Bound Bottom")
		(35 "F.Fab" user "Ref Des/Assembly Top")
		(33 "B.Fab" user "Ref Des/Assembly Bottom")
	)
	(footprint ""
		(layer "F.Cu")
		(at 29.337 -94.234 -90)
		(property "Reference" "R128"
			(at -4.953 0.84963 90)
			(unlocked yes)
			(layer "F.SilkS")
			(effects
				(font
					(size 0.7874 0.5842)
					(thickness 0.1524)
				)
			)
		)
		(property "Value" "VAL*"
			(at 0.02032 2.13233 270)
			(unlocked yes)
			(layer "F.Fab")
			(hide yes)
			(effects
				(font
					(size 0.7874 0.5842)
					(thickness 0.1524)
				)
			)
		)
		(property "Tolerance" "TOL*"
			(at 0.044704 3.05435 270)
			(unlocked yes)
			(layer "Cmts.User")
			(hide yes)
			(effects
				(font
					(size 0.7874 0.5842)
					(thickness 0.1524)
				)
			)
		)
		(property "User Part Number" "PARTNUM*"
			(at 0.02032 4.024884 270)
			(unlocked yes)
			(layer "Cmts.User")
			(hide yes)
			(effects
				(font
					(size 0.7874 0.5842)
					(thickness 0.1524)
				)
			)
		)
		(property "Device Type" "RESISTOR-G155-100R0-J0,0OHM,-"
			(at 0.008382 1.210564 270)
			(unlocked yes)
			(layer "F.Fab")
			(hide yes)
			(effects
				(font
					(size 0.7874 0.5842)
					(thickness 0.1524)
				)
			)
		)
		(duplicate_pad_numbers_are_jumpers no)
		(fp_line
			(start -1.143 0.5588)
			(end 1.143 0.5588)
			(stroke
				(width 0.1)
				(type default)
			)
			(layer "F.SilkS")
		)
		(fp_line
			(start 1.143 0.5588)
			(end 1.143 -0.5588)
			(stroke
				(width 0.1)
				(type default)
			)
			(layer "F.SilkS")
		)
		(fp_line
			(start -1.143 -0.5588)
			(end -1.143 0.5588)
			(stroke
				(width 0.1)
				(type default)
			)
			(layer "F.SilkS")
		)
		(fp_line
			(start 1.143 -0.5588)
			(end -1.143 -0.5588)
			(stroke
				(width 0.1)
				(type default)
			)
			(layer "F.SilkS")
		)
		(fp_poly
			(pts
				(xy -1.143 0.5588) (xy 1.143 0.5588) (xy 1.143 -0.5588) (xy -1.143 -0.5588)
			)
			(stroke
				(width 0)
				(type default)
			)
			(fill no)
			(layer "F.CrtYd")
		)
		(fp_line
			(start -0.508 0.3048)
			(end 0.508 0.3048)
			(stroke
				(width 0.1)
				(type default)
			)
			(layer "F.Fab")
		)
		(fp_line
			(start 0.508 0.3048)
			(end 0.508 -0.3048)
			(stroke
				(width 0.1)
				(type default)
			)
			(layer "F.Fab")
		)
		(fp_line
			(start -0.508 -0.3048)
			(end -0.508 0.3048)
			(stroke
				(width 0.1)
				(type default)
			)
			(layer "F.Fab")
		)
		(fp_line
			(start 0.508 -0.3048)
			(end -0.508 -0.3048)
			(stroke
				(width 0.1)
				(type default)
			)
			(layer "F.Fab")
		)
		(pad "1" smd rect
			(at -0.5334 0 270)
			(size 0.7112 0.6096)
			(layers "F.Cu" "F.Mask" "F.Paste")
			(net "FT_USB_DM")
		)
		(pad "2" smd rect
			(at 0.5334 0 270)
			(size 0.7112 0.6096)
			(layers "F.Cu" "F.Mask" "F.Paste")
			(net "R_FT_USB_DM")
		)
		(zone
			(layer "F.Cu")
			(hatch none 0.5)
			(connect_pads
				(clearance 0)
			)
			(min_thickness 0.25)
			(keepout
				(tracks not_allowed)
				(vias allowed)
				(pads allowed)
				(copperpour not_allowed)
				(footprints allowed)
			)
			(placement
				(enabled no)
				(sheetname "")
			)
			(fill
				(thermal_gap 0.5)
				(thermal_bridge_width 0.5)
				(island_removal_mode 0)
			)
			(polygon
				(pts
					(xy 29.0322 -94.3102) (xy 29.0322 -94.1578) (xy 29.6418 -94.1578) (xy 29.6418 -94.3102)
				)
			)
		)
		(zone
			(layer "F.Cu")
			(hatch none 0.5)
			(connect_pads
				(clearance 0)
			)
			(min_thickness 0.25)
			(keepout
				(tracks allowed)
				(vias not_allowed)
				(pads allowed)
				(copperpour not_allowed)
				(footprints allowed)
			)
			(placement
				(enabled no)
				(sheetname "")
			)
			(fill
				(thermal_gap 0.5)
				(thermal_bridge_width 0.5)
				(island_removal_mode 0)
			)
			(polygon
				(pts
					(xy 29.0322 -94.3102) (xy 29.0322 -94.1578) (xy 29.6418 -94.1578) (xy 29.6418 -94.3102)
				)
			)
		)
	)
	(footprint ""
		(layer "F.Cu")
		(at 42.4434 -103.9114)
		(property "Reference" "C33"
			(at 3.9116 -1.59893 0)
			(unlocked yes)
			(layer "F.SilkS")
			(effects
				(font
					(size 0.7874 0.5842)
					(thickness 0.1524)
				)
			)
		)
		(property "Value" "VAL*"
			(at 0.0762 2.067306 0)
			(unlocked yes)
			(layer "F.Fab")
			(hide yes)
			(effects
				(font
					(size 0.7874 0.5842)
					(thickness 0.1524)
				)
			)
		)
		(property "Device Type" "CAPACITOR-G105-0B104-EK,0.1UF,A"
			(at 0.0508 1.127506 0)
			(unlocked yes)
			(layer "F.Fab")
			(hide yes)
			(effects
				(font
					(size 0.7874 0.5842)
					(thickness 0.1524)
				)
			)
		)
		(property "User Part Number" "PARTNUM*"
			(at 0.1016 4.023106 0)
			(unlocked yes)
			(layer "Cmts.User")
			(hide yes)
			(effects
				(font
					(size 0.7874 0.5842)
					(thickness 0.1524)
				)
			)
		)
		(property "Tolerance" "TOL*"
			(at 0.0762 3.032506 0)
			(unlocked yes)
			(layer "Cmts.User")
			(hide yes)
			(effects
				(font
					(size 0.7874 0.5842)
					(thickness 0.1524)
				)
			)
		)
		(duplicate_pad_numbers_are_jumpers no)
		(fp_line
			(start -1.143 -0.5588)
			(end -1.143 0.5588)
			(stroke
				(width 0.1)
				(type default)
			)
			(layer "F.SilkS")
		)
		(fp_line
			(start -1.143 0.5588)
			(end 1.143 0.5588)
			(stroke
				(width 0.1)
				(type default)
			)
			(layer "F.SilkS")
		)
		(fp_line
			(start 1.143 -0.5588)
			(end -1.143 -0.5588)
			(stroke
				(width 0.1)
				(type default)
			)
			(layer "F.SilkS")
		)
		(fp_line
			(start 1.143 0.5588)
			(end 1.143 -0.5588)
			(stroke
				(width 0.1)
				(type default)
			)
			(layer "F.SilkS")
		)
		(fp_rect
			(start 1.143 -0.5588)
			(end -1.143 0.5588)
			(stroke
				(width 0)
				(type default)
			)
			(fill no)
			(layer "F.CrtYd")
		)
		(fp_line
			(start -0.508 -0.3048)
			(end -0.508 0.3048)
			(stroke
				(width 0.1)
				(type default)
			)
			(layer "F.Fab")
		)
		(fp_line
			(start -0.508 0.3048)
			(end 0.508 0.3048)
			(stroke
				(width 0.1)
				(type default)
			)
			(layer "F.Fab")
		)
		(fp_line
			(start 0.508 -0.3048)
			(end -0.508 -0.3048)
			(stroke
				(width 0.1)
				(type default)
			)
			(layer "F.Fab")
		)
		(fp_line
			(start 0.508 0.3048)
			(end 0.508 -0.3048)
			(stroke
				(width 0.1)
				(type default)
			)
			(layer "F.Fab")
		)
		(pad "1" smd rect
			(at -0.5334 0)
			(size 0.7112 0.6096)
			(layers "F.Cu" "F.Mask" "F.Paste")
			(net "VIN_XP5R0V")
		)
		(pad "2" smd rect
			(at 0.5334 0)
			(size 0.7112 0.6096)
			(layers "F.Cu" "F.Mask" "F.Paste")
			(net "SG")
		)
		(zone
			(layer "F.Cu")
			(hatch none 0.5)
			(connect_pads
				(clearance 0)
			)
			(min_thickness 0.25)
			(keepout
				(tracks allowed)
				(vias not_allowed)
				(pads allowed)
				(copperpour not_allowed)
				(footprints allowed)
			)
			(placement
				(enabled no)
				(sheetname "")
			)
			(fill
				(thermal_gap 0.5)
				(thermal_bridge_width 0.5)
				(island_removal_mode 0)
			)
			(polygon
				(pts
					(xy 42.5196 -104.2162) (xy 42.3672 -104.2162) (xy 42.3672 -103.6066) (xy 42.5196 -103.6066)
				)
			)
		)
	)
)
